# BASEBOARD_FAB2 (Tioga Pass) — schematic netlist excerpt (pin names and nets, part order shuffled) for the footprints in the layout excerpt that follows; sources: Cadence DE-HDL packaged netlist, KiCad conversion of Wiwynn_Tioga_Pass_MB.brd

J4G2  SCONN288_H44441004  SCONN  pkg PIP  page 45
  \12v\(1)  = P12V_NVDIMM_ABC
  VSS(93)  = GND
  DQ(4)  = M_B_DQ<5>
  VSS(92)  = GND
  DQ(0)  = M_B_DQ<1>
  VSS(91)  = GND
  DQS9P  = M_B_DQS_DP<9>
  DQS9N  = M_B_DQS_DN<9>
  VSS(90)  = GND
  DQ(6)  = M_B_DQ<7>
  VSS(89)  = GND
  DQ(2)  = M_B_DQ<3>
  VSS(88)  = GND
  DQ(12)  = M_B_DQ<13>
  VSS(87)  = GND
  DQ(8)  = M_B_DQ<9>
  VSS(86)  = GND
  DQS10P  = M_B_DQS_DP<10>
  DQS10N  = M_B_DQS_DN<10>
  VSS(85)  = GND
  DQ(14)  = M_B_DQ<15>
  VSS(84)  = GND
  DQ(10)  = M_B_DQ<11>
  VSS(83)  = GND
  DQ(20)  = M_B_DQ<21>
  VSS(82)  = GND
  DQ(16)  = M_B_DQ<17>
  VSS(81)  = GND
  DQS11P  = M_B_DQS_DP<11>
  DQS11N  = M_B_DQS_DN<11>
  VSS(80)  = GND
  DQ(22)  = M_B_DQ<23>
  VSS(79)  = GND
  DQ(18)  = M_B_DQ<19>
  VSS(78)  = GND
  DQ(28)  = M_B_DQ<29>
  VSS(77)  = GND
  DQ(24)  = M_B_DQ<25>
  VSS(76)  = GND
  DQS12P  = M_B_DQS_DP<12>
  DQS12N  = M_B_DQS_DN<12>
  VSS(75)  = GND
  DQ(30)  = M_B_DQ<31>
  VSS(74)  = GND
  DQ(26)  = M_B_DQ<27>
  VSS(73)  = GND
  CB(4)  = M_B_ECC<5>
  VSS(72)  = GND
  CB(0)  = M_B_ECC<1>
  VSS(71)  = GND
  DQS17P  = M_B_DQS_DP<17>
  DQS17N  = M_B_DQS_DN<17>
  VSS(70)  = GND
  CB(6)  = M_B_ECC<7>
  VSS(69)  = GND
  CB(2)  = M_B_ECC<3>
  VSS(68)  = GND
  RESET_N  = M_ABC_RST_N
  VDD(25)  = PVDDQ_ABC
  CKE(0)  = M_B_CKE<0>
  VDD(24)  = PVDDQ_ABC
  ACT_N  = M_B_ACT_N
  BG(0)  = M_B_BG<0>
  VDD(23)  = PVDDQ_ABC
  A12  = M_B_MA<12>
  A9  = M_B_MA<9>
  VDD(22)  = PVDDQ_ABC
  A8  = M_B_MA<8>
  A6  = M_B_MA<6>
  VDD(21)  = PVDDQ_ABC
  A3  = M_B_MA<3>
  A1  = M_B_MA<1>
  VDD(20)  = PVDDQ_ABC
  CK0P  = M_B_CLK_DP<0>
  CK0N  = M_B_CLK_DN<0>
  VDD(19)  = PVDDQ_ABC
  VTT(1)  = PVTT_ABC
  EVENT_N  = FM_DIMM_EVENT_COD_N
  A0  = M_B_MA<0>
  VDD(18)  = PVDDQ_ABC
  BA(0)  = M_B_BA<0>
  A16_RAS_N  = M_B_MA<16>
  VDD(17)  = PVDDQ_ABC
  S0_N  = M_B_CS_N<0>
  VDD(16)  = PVDDQ_ABC
  A15_CAS_N  = M_B_MA<15>
  ODT(0)  = M_B_ODT<0>
  VDD(15)  = PVDDQ_ABC
  S1_N  = M_B_CS_N<1>
  VDD(14)  = PVDDQ_ABC
  ODT(1)  = M_B_ODT<1>
  VDD(13)  = PVDDQ_ABC
  S2_N_C(0)  = M_B_CS_N<2>
  VSS(67)  = GND
  DQ(36)  = M_B_DQ<37>
  VSS(66)  = GND
  DQ(32)  = M_B_DQ<33>
  VSS(65)  = GND
  DQS13P  = M_B_DQS_DP<13>
  DQS13N  = M_B_DQS_DN<13>
  VSS(64)  = GND
  DQ(38)  = M_B_DQ<39>
  VSS(63)  = GND
  DQ(34)  = M_B_DQ<35>
  VSS(62)  = GND
  DQ(44)  = M_B_DQ<45>
  VSS(61)  = GND
  DQ(40)  = M_B_DQ<41>
  VSS(60)  = GND
  DQS14P  = M_B_DQS_DP<14>
  DQS14N  = M_B_DQS_DN<14>
  VSS(59)  = GND
  DQ(46)  = M_B_DQ<47>
  VSS(58)  = GND
  DQ(42)  = M_B_DQ<43>
  VSS(57)  = GND
  DQ(52)  = M_B_DQ<53>
  VSS(56)  = GND
  DQ(48)  = M_B_DQ<49>
  VSS(55)  = GND
  DQS15P  = M_B_DQS_DP<15>
  DQS15N  = M_B_DQS_DN<15>
  VSS(54)  = GND
  DQ(54)  = M_B_DQ<55>
  VSS(53)  = GND
  DQ(50)  = M_B_DQ<51>
  VSS(52)  = GND
  DQ(60)  = M_B_DQ<61>
  VSS(51)  = GND
  DQ(56)  = M_B_DQ<57>
  VSS(50)  = GND
  DQS16P  = M_B_DQS_DP<16>
  DQS16N  = M_B_DQS_DN<16>
  VSS(49)  = GND
  DQ(62)  = M_B_DQ<63>
  VSS(48)  = GND
  DQ(58)  = M_B_DQ<59>
  VSS(47)  = GND
  SA(0)  = GND
  SA(1)  = PVPP_ABC
  SCL  = SMB_DDR_ABC_VPP_SCL
  VPP(4)  = PVPP_ABC
  VPP(3)  = PVPP_ABC
  RFU(2)  = TP_CH_B_DIMM_B0_RFU_2
  \12v\(0)  = P12V_NVDIMM_ABC
  VREFCA  = M_B_VREF
  VSS(46)  = GND
  DQ(5)  = M_B_DQ<4>
  VSS(45)  = GND
  DQ(1)  = M_B_DQ<0>
  VSS(44)  = GND
  DQS0N  = M_B_DQS_DN<0>
  DQS0P  = M_B_DQS_DP<0>
  VSS(43)  = GND
  DQ(7)  = M_B_DQ<6>
  VSS(42)  = GND
  DQ(3)  = M_B_DQ<2>
  VSS(41)  = GND
  DQ(13)  = M_B_DQ<12>
  VSS(40)  = GND
  DQ(9)  = M_B_DQ<8>
  VSS(39)  = GND
  DQS1N  = M_B_DQS_DN<1>
  DQS1P  = M_B_DQS_DP<1>
  VSS(38)  = GND
  DQ(15)  = M_B_DQ<14>
  VSS(37)  = GND
  DQ(11)  = M_B_DQ<10>
  VSS(36)  = GND
  DQ(21)  = M_B_DQ<20>
  VSS(35)  = GND
  DQ(17)  = M_B_DQ<16>
  VSS(34)  = GND
  DQS2N  = M_B_DQS_DN<2>
  DQS2P  = M_B_DQS_DP<2>
  VSS(33)  = GND
  DQ(23)  = M_B_DQ<22>
  VSS(32)  = GND
  DQ(19)  = M_B_DQ<18>
  VSS(31)  = GND
  DQ(29)  = M_B_DQ<28>
  VSS(30)  = GND
  DQ(25)  = M_B_DQ<24>
  VSS(29)  = GND
  DQS3N  = M_B_DQS_DN<3>
  DQS3P  = M_B_DQS_DP<3>
  VSS(28)  = GND
  DQ(31)  = M_B_DQ<30>
  VSS(27)  = GND
  DQ(27)  = M_B_DQ<26>
  VSS(26)  = GND
  CB(5)  = M_B_ECC<4>
  VSS(25)  = GND
  CB(1)  = M_B_ECC<0>
  VSS(24)  = GND
  DQS8N  = M_B_DQS_DN<8>
  DQS8P  = M_B_DQS_DP<8>
  VSS(23)  = GND
  CB(7)  = M_B_ECC<6>
  VSS(22)  = GND
  CB(3)  = M_B_ECC<2>
  VSS(21)  = GND
  CKE(1)  = M_B_CKE<1>
  VDD(12)  = PVDDQ_ABC
  RFU(0)  = TP_CH_B_DIMM_B0_RFU_0
  VDD(11)  = PVDDQ_ABC
  BG(1)  = M_B_BG<1>
  ALERT_N  = M_B_ALERT_N
  VDD(10)  = PVDDQ_ABC
  A11  = M_B_MA<11>
  A7  = M_B_MA<7>
  VDD(9)  = PVDDQ_ABC
  A5  = M_B_MA<5>
  A4  = M_B_MA<4>
  VDD(8)  = PVDDQ_ABC
  A2  = M_B_MA<2>
  VDD(7)  = PVDDQ_ABC
  CK1P  = M_B_CLK_DP<1>
  CK1N  = M_B_CLK_DN<1>
  VDD(6)  = PVDDQ_ABC
  VTT(0)  = PVTT_ABC
  PAR  = M_B_PAR
  VDD(5)  = PVDDQ_ABC
  BA(1)  = M_B_BA<1>
  A10  = M_B_MA<10>
  VDD(4)  = PVDDQ_ABC
  RFU(1)  = TP_CH_B_DIMM_B0_RFU_1
  A14_WE_N  = M_B_MA<14>
  VDD(3)  = PVDDQ_ABC
  SAVE_N_NC  = FM_ADR_COMPLETE_ABC_N
  VDD(2)  = PVDDQ_ABC
  A13  = M_B_MA<13>
  VDD(1)  = PVDDQ_ABC
  A17  = M_B_MA<17>
  C(2)  = M_B_C<2>
  VDD(0)  = PVDDQ_ABC
  S3_N_C(1)  = M_B_CS_N<3>
  SA(2)  = GND
  VSS(20)  = GND
  DQ(37)  = M_B_DQ<36>
  VSS(19)  = GND
  DQ(33)  = M_B_DQ<32>
  VSS(18)  = GND
  DQS4N  = M_B_DQS_DN<4>
  DQS4P  = M_B_DQS_DP<4>
  VSS(17)  = GND
  DQ(39)  = M_B_DQ<38>
  VSS(16)  = GND
  DQ(35)  = M_B_DQ<34>
  VSS(15)  = GND
  DQ(45)  = M_B_DQ<44>
  VSS(14)  = GND
  DQ(41)  = M_B_DQ<40>
  VSS(13)  = GND
  DQS5N  = M_B_DQS_DN<5>
  DQS5P  = M_B_DQS_DP<5>
  VSS(12)  = GND
  DQ(47)  = M_B_DQ<46>
  VSS(11)  = GND
  DQ(43)  = M_B_DQ<42>
  VSS(10)  = GND
  DQ(53)  = M_B_DQ<52>
  VSS(9)  = GND
  DQ(49)  = M_B_DQ<48>
  VSS(8)  = GND
  DQS6N  = M_B_DQS_DN<6>
  DQS6P  = M_B_DQS_DP<6>
  VSS(7)  = GND
  DQ(55)  = M_B_DQ<54>
  VSS(6)  = GND
  DQ(51)  = M_B_DQ<50>
  VSS(5)  = GND
  DQ(61)  = M_B_DQ<60>
  VSS(4)  = GND
  DQ(57)  = M_B_DQ<56>
  VSS(3)  = GND
  DQS7N  = M_B_DQS_DN<7>
  DQS7P  = M_B_DQS_DP<7>
  VSS(2)  = GND
  DQ(63)  = M_B_DQ<62>
  VSS(1)  = GND
  DQ(59)  = M_B_DQ<58>
  VSS(0)  = GND
  VDDSPD  = PVPP_ABC
  SDA  = SMB_DDR_ABC_VPP_SDA
  VPP(1)  = PVPP_ABC
  VPP(0)  = PVPP_ABC
  VPP(2)  = PVPP_ABC

(kicad_pcb
	(version 20260206)
	(generator "pcbnew")
	(generator_version "10.0")
	(general
		(thickness 1.6)
		(legacy_teardrops no)
	)
	(paper "A4")
	(title_block
		(title "Wiwynn_Tioga_Pass_MB.brd")
		(comment 1 "Tioga Pass / footprint 1899 of 4770 (J4G2), pads 252-291 of 291")
	)
	(layers
		(0 "F.Cu" signal "TOP")
		(4 "In1.Cu" signal "L2GND")
		(6 "In2.Cu" signal "L3")
		(8 "In3.Cu" signal "L4GND")
		(10 "In4.Cu" signal "L5")
		(12 "In5.Cu" signal "L6GND")
		(14 "In6.Cu" signal "L7VCC")
		(16 "In7.Cu" signal "L8VCC")
		(18 "In8.Cu" signal "L9GND")
		(20 "In9.Cu" signal "L10")
		(22 "In10.Cu" signal "L11GND")
		(24 "In11.Cu" signal "L12")
		(26 "In12.Cu" signal "L13GND")
		(2 "B.Cu" signal "BOTTOM")
		(9 "F.Adhes" user "F.Adhesive")
		(11 "B.Adhes" user "B.Adhesive")
		(13 "F.Paste" user "Package Geometry/Pastemask Top")
		(15 "B.Paste" user "Package Geometry/Pastemask Bottom")
		(5 "F.SilkS" user "Ref Des/Silkscreen Top")
		(7 "B.SilkS" user "Ref Des/Silkscreen Bottom")
		(1 "F.Mask" user "Board Geometry/Soldermask Top")
		(3 "B.Mask" user "Board Geometry/Soldermask Bottom")
		(17 "Dwgs.User" user "User.Drawings")
		(19 "Cmts.User" user "User.Comments")
		(21 "Eco1.User" user "User.Eco1")
		(23 "Eco2.User" user "User.Eco2")
		(25 "Edge.Cuts" user "Board Geometry/Outline")
		(27 "Margin" user)
		(31 "F.CrtYd" user "Package Geometry/Place Bound Top")
		(29 "B.CrtYd" user "Package Geometry/Place Bound Bottom")
		(35 "F.Fab" user "Ref Des/Assembly Top")
		(33 "B.Fab" user "Ref Des/Assembly Bottom")
	)
	(footprint ""
		(layer "F.Cu")
		(at 194.700398 -5.822442 90)
		(property "Reference" "J4G2"
			(at 6.596888 37.58311 0)
			(unlocked yes)
			(layer "F.SilkS")
			(effects
				(font
					(size 0.7874 0.5842)
					(thickness 0.1524)
				)
				(justify left)
			)
		)
		(property "Value" ""
			(at 0 0 90)
			(layer "F.Fab")
			(effects
				(font
					(size 1.27 1.27)
				)
			)
		)
		(duplicate_pad_numbers_are_jumpers no)
		(pad "249" smd rect
			(at 4.59994 93.49994 90)
			(size 1.8034 0.508)
			(layers "F.Cu" "F.Mask" "F.Paste")
			(net "M_B_DQ<34>")
		)
		(pad "250" smd rect
			(at 4.59994 94.350078 90)
			(size 1.8034 0.508)
			(layers "F.Cu" "F.Mask" "F.Paste")
			(net "GND")
		)
		(pad "251" smd rect
			(at 4.59994 95.199962 90)
			(size 1.8034 0.508)
			(layers "F.Cu" "F.Mask" "F.Paste")
			(net "M_B_DQ<44>")
		)
		(pad "252" smd rect
			(at 4.59994 96.0501 90)
			(size 1.8034 0.508)
			(layers "F.Cu" "F.Mask" "F.Paste")
			(net "GND")
		)
		(pad "253" smd rect
			(at 4.59994 96.899984 90)
			(size 1.8034 0.508)
			(layers "F.Cu" "F.Mask" "F.Paste")
			(net "M_B_DQ<40>")
		)
		(pad "254" smd rect
			(at 4.59994 97.750122 90)
			(size 1.8034 0.508)
			(layers "F.Cu" "F.Mask" "F.Paste")
			(net "GND")
		)
		(pad "255" smd rect
			(at 4.59994 98.600006 90)
			(size 1.8034 0.508)
			(layers "F.Cu" "F.Mask" "F.Paste")
			(net "M_B_DQS_DN<5>")
		)
		(pad "256" smd rect
			(at 4.59994 99.44989 90)
			(size 1.8034 0.508)
			(layers "F.Cu" "F.Mask" "F.Paste")
			(net "M_B_DQS_DP<5>")
		)
		(pad "257" smd rect
			(at 4.59994 100.300028 90)
			(size 1.8034 0.508)
			(layers "F.Cu" "F.Mask" "F.Paste")
			(net "GND")
		)
		(pad "258" smd rect
			(at 4.59994 101.149912 90)
			(size 1.8034 0.508)
			(layers "F.Cu" "F.Mask" "F.Paste")
			(net "M_B_DQ<46>")
		)
		(pad "259" smd rect
			(at 4.59994 102.00005 90)
			(size 1.8034 0.508)
			(layers "F.Cu" "F.Mask" "F.Paste")
			(net "GND")
		)
		(pad "260" smd rect
			(at 4.59994 102.849934 90)
			(size 1.8034 0.508)
			(layers "F.Cu" "F.Mask" "F.Paste")
			(net "M_B_DQ<42>")
		)
		(pad "261" smd rect
			(at 4.59994 103.700072 90)
			(size 1.8034 0.508)
			(layers "F.Cu" "F.Mask" "F.Paste")
			(net "GND")
		)
		(pad "262" smd rect
			(at 4.59994 104.549956 90)
			(size 1.8034 0.508)
			(layers "F.Cu" "F.Mask" "F.Paste")
			(net "M_B_DQ<52>")
		)
		(pad "263" smd rect
			(at 4.59994 105.400094 90)
			(size 1.8034 0.508)
			(layers "F.Cu" "F.Mask" "F.Paste")
			(net "GND")
		)
		(pad "264" smd rect
			(at 4.59994 106.249978 90)
			(size 1.8034 0.508)
			(layers "F.Cu" "F.Mask" "F.Paste")
			(net "M_B_DQ<48>")
		)
		(pad "265" smd rect
			(at 4.59994 107.100116 90)
			(size 1.8034 0.508)
			(layers "F.Cu" "F.Mask" "F.Paste")
			(net "GND")
		)
		(pad "266" smd rect
			(at 4.59994 107.95 90)
			(size 1.8034 0.508)
			(layers "F.Cu" "F.Mask" "F.Paste")
			(net "M_B_DQS_DN<6>")
		)
		(pad "267" smd rect
			(at 4.59994 108.799884 90)
			(size 1.8034 0.508)
			(layers "F.Cu" "F.Mask" "F.Paste")
			(net "M_B_DQS_DP<6>")
		)
		(pad "268" smd rect
			(at 4.59994 109.650022 90)
			(size 1.8034 0.508)
			(layers "F.Cu" "F.Mask" "F.Paste")
			(net "GND")
		)
		(pad "269" smd rect
			(at 4.59994 110.499906 90)
			(size 1.8034 0.508)
			(layers "F.Cu" "F.Mask" "F.Paste")
			(net "M_B_DQ<54>")
		)
		(pad "270" smd rect
			(at 4.59994 111.350044 90)
			(size 1.8034 0.508)
			(layers "F.Cu" "F.Mask" "F.Paste")
			(net "GND")
		)
		(pad "271" smd rect
			(at 4.59994 112.199928 90)
			(size 1.8034 0.508)
			(layers "F.Cu" "F.Mask" "F.Paste")
			(net "M_B_DQ<50>")
		)
		(pad "272" smd rect
			(at 4.59994 113.050066 90)
			(size 1.8034 0.508)
			(layers "F.Cu" "F.Mask" "F.Paste")
			(net "GND")
		)
		(pad "273" smd rect
			(at 4.59994 113.89995 90)
			(size 1.8034 0.508)
			(layers "F.Cu" "F.Mask" "F.Paste")
			(net "M_B_DQ<60>")
		)
		(pad "274" smd rect
			(at 4.59994 114.750088 90)
			(size 1.8034 0.508)
			(layers "F.Cu" "F.Mask" "F.Paste")
			(net "GND")
		)
		(pad "275" smd rect
			(at 4.59994 115.599972 90)
			(size 1.8034 0.508)
			(layers "F.Cu" "F.Mask" "F.Paste")
			(net "M_B_DQ<56>")
		)
		(pad "276" smd rect
			(at 4.59994 116.45011 90)
			(size 1.8034 0.508)
			(layers "F.Cu" "F.Mask" "F.Paste")
			(net "GND")
		)
		(pad "277" smd rect
			(at 4.59994 117.299994 90)
			(size 1.8034 0.508)
			(layers "F.Cu" "F.Mask" "F.Paste")
			(net "M_B_DQS_DN<7>")
		)
		(pad "278" smd rect
			(at 4.59994 118.149878 90)
			(size 1.8034 0.508)
			(layers "F.Cu" "F.Mask" "F.Paste")
			(net "M_B_DQS_DP<7>")
		)
		(pad "279" smd rect
			(at 4.59994 119.000016 90)
			(size 1.8034 0.508)
			(layers "F.Cu" "F.Mask" "F.Paste")
			(net "GND")
		)
		(pad "280" smd rect
			(at 4.59994 119.8499 90)
			(size 1.8034 0.508)
			(layers "F.Cu" "F.Mask" "F.Paste")
			(net "M_B_DQ<62>")
		)
		(pad "281" smd rect
			(at 4.59994 120.700038 90)
			(size 1.8034 0.508)
			(layers "F.Cu" "F.Mask" "F.Paste")
			(net "GND")
		)
		(pad "282" smd rect
			(at 4.59994 121.549922 90)
			(size 1.8034 0.508)
			(layers "F.Cu" "F.Mask" "F.Paste")
			(net "M_B_DQ<58>")
		)
		(pad "283" smd rect
			(at 4.59994 122.40006 90)
			(size 1.8034 0.508)
			(layers "F.Cu" "F.Mask" "F.Paste")
			(net "GND")
		)
		(pad "284" smd rect
			(at 4.59994 123.249944 90)
			(size 1.8034 0.508)
			(layers "F.Cu" "F.Mask" "F.Paste")
			(net "PVPP_ABC")
		)
		(pad "285" smd rect
			(at 4.59994 124.100082 90)
			(size 1.8034 0.508)
			(layers "F.Cu" "F.Mask" "F.Paste")
			(net "SMB_DDR_ABC_VPP_SDA")
		)
		(pad "286" smd rect
			(at 4.59994 124.949966 90)
			(size 1.8034 0.508)
			(layers "F.Cu" "F.Mask" "F.Paste")
			(net "PVPP_ABC")
		)
		(pad "287" smd rect
			(at 4.59994 125.800104 90)
			(size 1.8034 0.508)
			(layers "F.Cu" "F.Mask" "F.Paste")
			(net "PVPP_ABC")
		)
		(pad "288" smd rect
			(at 4.59994 126.649988 90)
			(size 1.8034 0.508)
			(layers "F.Cu" "F.Mask" "F.Paste")
			(net "PVPP_ABC")
		)
	)
)
